(kicad_pcb
	(version 20260206)
	(generator "pcbnew")
	(generator_version "10.0")
	(general
		(thickness 1.6)
		(legacy_teardrops no)
	)
	(paper "A4")
	(title_block
		(title "Wiwynn_Tioga_Pass_MB.brd")
		(comment 1 "Tioga Pass / footprints 3195-3201 of 4770")
	)
	(layers
		(0 "F.Cu" signal "TOP")
		(4 "In1.Cu" signal "L2GND")
		(6 "In2.Cu" signal "L3")
		(8 "In3.Cu" signal "L4GND")
		(10 "In4.Cu" signal "L5")
		(12 "In5.Cu" signal "L6GND")
		(14 "In6.Cu" signal "L7VCC")
		(16 "In7.Cu" signal "L8VCC")
		(18 "In8.Cu" signal "L9GND")
		(20 "In9.Cu" signal "L10")
		(22 "In10.Cu" signal "L11GND")
		(24 "In11.Cu" signal "L12")
		(26 "In12.Cu" signal "L13GND")
		(2 "B.Cu" signal "BOTTOM")
		(9 "F.Adhes" user "F.Adhesive")
		(11 "B.Adhes" user "B.Adhesive")
		(13 "F.Paste" user "Package Geometry/Pastemask Top")
		(15 "B.Paste" user "Package Geometry/Pastemask Bottom")
		(5 "F.SilkS" user "Ref Des/Silkscreen Top")
		(7 "B.SilkS" user "Ref Des/Silkscreen Bottom")
		(1 "F.Mask" user "Board Geometry/Soldermask Top")
		(3 "B.Mask" user "Board Geometry/Soldermask Bottom")
		(17 "Dwgs.User" user "User.Drawings")
		(19 "Cmts.User" user "User.Comments")
		(21 "Eco1.User" user "User.Eco1")
		(23 "Eco2.User" user "User.Eco2")
		(25 "Edge.Cuts" user "Board Geometry/Outline")
		(27 "Margin" user)
		(31 "F.CrtYd" user "Package Geometry/Place Bound Top")
		(29 "B.CrtYd" user "Package Geometry/Place Bound Bottom")
		(35 "F.Fab" user "Ref Des/Assembly Top")
		(33 "B.Fab" user "Ref Des/Assembly Bottom")
	)
	(footprint ""
		(layer "B.Cu")
		(at 117.1956 -72.644 -90)
		(property "Reference" "R7P17"
			(at 0 0 90)
			(layer "B.SilkS")
			(hide yes)
			(effects
				(font
					(size 1.27 1.27)
				)
				(justify mirror)
			)
		)
		(property "Value" ""
			(at 0 0 90)
			(layer "B.Fab")
			(effects
				(font
					(size 1.27 1.27)
				)
				(justify mirror)
			)
		)
		(duplicate_pad_numbers_are_jumpers no)
		(fp_poly
			(pts
				(xy 0.2794 -0.1016) (xy -0.2794 -0.1016) (xy -0.2794 0.9906) (xy 0.2794 0.9906)
			)
			(stroke
				(width 0)
				(type default)
			)
			(fill no)
			(layer "B.CrtYd")
		)
		(fp_line
			(start -0.2794 0.9906)
			(end -0.2794 -0.1016)
			(stroke
				(width 0.1)
				(type default)
			)
			(layer "B.Fab")
		)
		(fp_line
			(start 0.2794 0.9906)
			(end -0.2794 0.9906)
			(stroke
				(width 0.1)
				(type default)
			)
			(layer "B.Fab")
		)
		(fp_line
			(start -0.2794 -0.1016)
			(end 0.2794 -0.1016)
			(stroke
				(width 0.1)
				(type default)
			)
			(layer "B.Fab")
		)
		(fp_line
			(start 0.2794 -0.1016)
			(end 0.2794 0.9906)
			(stroke
				(width 0.1)
				(type default)
			)
			(layer "B.Fab")
		)
		(pad "1" smd rect
			(at 0 0 90)
			(size 0.508 0.508)
			(layers "B.Cu" "B.Mask" "B.Paste")
			(net "A_CPU1_GHJ_RCOMP1")
		)
		(pad "2" smd rect
			(at 0 0.889 90)
			(size 0.508 0.508)
			(layers "B.Cu" "B.Mask" "B.Paste")
			(net "GND")
		)
		(zone
			(layer "B.Cu")
			(hatch none 0.5)
			(connect_pads
				(clearance 0)
			)
			(min_thickness 0.25)
			(keepout
				(tracks not_allowed)
				(vias allowed)
				(pads allowed)
				(copperpour not_allowed)
				(footprints allowed)
			)
			(placement
				(enabled no)
				(sheetname "")
			)
			(fill
				(thermal_gap 0.5)
				(thermal_bridge_width 0.5)
				(island_removal_mode 0)
			)
			(polygon
				(pts
					(xy 116.5606 -72.39) (xy 116.5606 -72.898) (xy 116.9416 -72.898) (xy 116.9416 -72.39)
				)
			)
		)
		(zone
			(layer "B.Cu")
			(hatch none 0.5)
			(connect_pads
				(clearance 0)
			)
			(min_thickness 0.25)
			(keepout
				(tracks allowed)
				(vias not_allowed)
				(pads allowed)
				(copperpour not_allowed)
				(footprints allowed)
			)
			(placement
				(enabled no)
				(sheetname "")
			)
			(fill
				(thermal_gap 0.5)
				(thermal_bridge_width 0.5)
				(island_removal_mode 0)
			)
			(polygon
				(pts
					(xy 116.9416 -72.39) (xy 116.9416 -72.898) (xy 116.5606 -72.898) (xy 116.5606 -72.39)
				)
			)
		)
	)
	(footprint ""
		(layer "B.Cu")
		(at 93.105732 -12.888468 -90)
		(property "Reference" "C5G83"
			(at -1.14681 0.76708 0)
			(unlocked yes)
			(layer "B.SilkS")
			(effects
				(font
					(size 0.7874 0.5842)
					(thickness 0.1524)
				)
				(justify mirror)
			)
		)
		(property "Value" ""
			(at 0 0 90)
			(layer "B.Fab")
			(effects
				(font
					(size 1.27 1.27)
				)
				(justify mirror)
			)
		)
		(duplicate_pad_numbers_are_jumpers no)
		(fp_rect
			(start -0.4953 -0.2032)
			(end 0.4953 1.6002)
			(stroke
				(width 0)
				(type default)
			)
			(fill no)
			(layer "B.CrtYd")
		)
		(fp_line
			(start -0.4953 1.6002)
			(end 0.4953 1.6002)
			(stroke
				(width 0.1)
				(type default)
			)
			(layer "B.Fab")
		)
		(fp_line
			(start 0.4953 1.6002)
			(end 0.4953 -0.2032)
			(stroke
				(width 0.1)
				(type default)
			)
			(layer "B.Fab")
		)
		(fp_line
			(start -0.4953 -0.2032)
			(end -0.4953 1.6002)
			(stroke
				(width 0.1)
				(type default)
			)
			(layer "B.Fab")
		)
		(fp_line
			(start 0.4953 -0.2032)
			(end -0.4953 -0.2032)
			(stroke
				(width 0.1)
				(type default)
			)
			(layer "B.Fab")
		)
		(pad "1" smd rect
			(at 0 0 90)
			(size 0.762 0.889)
			(layers "B.Cu" "B.Mask" "B.Paste")
			(net "PVDDQ_GHJ")
		)
		(pad "2" smd rect
			(at 0 1.397 90)
			(size 0.762 0.889)
			(layers "B.Cu" "B.Mask" "B.Paste")
			(net "GND")
		)
		(zone
			(layer "B.Cu")
			(hatch none 0.5)
			(connect_pads
				(clearance 0)
			)
			(min_thickness 0.25)
			(keepout
				(tracks not_allowed)
				(vias allowed)
				(pads allowed)
				(copperpour not_allowed)
				(footprints allowed)
			)
			(placement
				(enabled no)
				(sheetname "")
			)
			(fill
				(thermal_gap 0.5)
				(thermal_bridge_width 0.5)
				(island_removal_mode 0)
			)
			(polygon
				(pts
					(xy 92.661232 -13.269468) (xy 92.153232 -13.269468) (xy 92.153232 -12.507468) (xy 92.661232 -12.507468)
				)
			)
		)
	)
	(footprint ""
		(layer "B.Cu")
		(at 378.53874 -67.21856)
		(property "Reference" "R2R2"
			(at 0 0 0)
			(layer "B.SilkS")
			(hide yes)
			(effects
				(font
					(size 1.27 1.27)
				)
				(justify mirror)
			)
		)
		(property "Value" ""
			(at 0 0 0)
			(layer "B.Fab")
			(effects
				(font
					(size 1.27 1.27)
				)
				(justify mirror)
			)
		)
		(duplicate_pad_numbers_are_jumpers no)
		(fp_poly
			(pts
				(xy 0.2794 -0.1016) (xy -0.2794 -0.1016) (xy -0.2794 0.9906) (xy 0.2794 0.9906)
			)
			(stroke
				(width 0)
				(type default)
			)
			(fill no)
			(layer "B.CrtYd")
		)
		(fp_line
			(start -0.2794 -0.1016)
			(end 0.2794 -0.1016)
			(stroke
				(width 0.1)
				(type default)
			)
			(layer "B.Fab")
		)
		(fp_line
			(start -0.2794 0.9906)
			(end -0.2794 -0.1016)
			(stroke
				(width 0.1)
				(type default)
			)
			(layer "B.Fab")
		)
		(fp_line
			(start 0.2794 -0.1016)
			(end 0.2794 0.9906)
			(stroke
				(width 0.1)
				(type default)
			)
			(layer "B.Fab")
		)
		(fp_line
			(start 0.2794 0.9906)
			(end -0.2794 0.9906)
			(stroke
				(width 0.1)
				(type default)
			)
			(layer "B.Fab")
		)
		(pad "1" smd rect
			(at 0 0 180)
			(size 0.508 0.508)
			(layers "B.Cu" "B.Mask" "B.Paste")
			(net "RST_RSMRST_R_N")
		)
		(pad "2" smd rect
			(at 0 0.889 180)
			(size 0.508 0.508)
			(layers "B.Cu" "B.Mask" "B.Paste")
			(net "RST_RSMRST_N")
		)
		(zone
			(layer "B.Cu")
			(hatch none 0.5)
			(connect_pads
				(clearance 0)
			)
			(min_thickness 0.25)
			(keepout
				(tracks allowed)
				(vias not_allowed)
				(pads allowed)
				(copperpour not_allowed)
				(footprints allowed)
			)
			(placement
				(enabled no)
				(sheetname "")
			)
			(fill
				(thermal_gap 0.5)
				(thermal_bridge_width 0.5)
				(island_removal_mode 0)
			)
			(polygon
				(pts
					(xy 378.79274 -66.96456) (xy 378.28474 -66.96456) (xy 378.28474 -66.58356) (xy 378.79274 -66.58356)
				)
			)
		)
		(zone
			(layer "B.Cu")
			(hatch none 0.5)
			(connect_pads
				(clearance 0)
			)
			(min_thickness 0.25)
			(keepout
				(tracks not_allowed)
				(vias allowed)
				(pads allowed)
				(copperpour not_allowed)
				(footprints allowed)
			)
			(placement
				(enabled no)
				(sheetname "")
			)
			(fill
				(thermal_gap 0.5)
				(thermal_bridge_width 0.5)
				(island_removal_mode 0)
			)
			(polygon
				(pts
					(xy 378.79274 -66.58356) (xy 378.28474 -66.58356) (xy 378.28474 -66.96456) (xy 378.79274 -66.96456)
				)
			)
		)
	)
	(footprint ""
		(layer "B.Cu")
		(at 169.770552 -23.562564 -90)
		(property "Reference" "R6T1"
			(at 0 0 90)
			(layer "B.SilkS")
			(hide yes)
			(effects
				(font
					(size 1.27 1.27)
				)
				(justify mirror)
			)
		)
		(property "Value" ""
			(at 0 0 90)
			(layer "B.Fab")
			(effects
				(font
					(size 1.27 1.27)
				)
				(justify mirror)
			)
		)
		(duplicate_pad_numbers_are_jumpers no)
		(fp_poly
			(pts
				(xy 0.2794 -0.1016) (xy -0.2794 -0.1016) (xy -0.2794 0.9906) (xy 0.2794 0.9906)
			)
			(stroke
				(width 0)
				(type default)
			)
			(fill no)
			(layer "B.CrtYd")
		)
		(fp_line
			(start -0.2794 0.9906)
			(end -0.2794 -0.1016)
			(stroke
				(width 0.1)
				(type default)
			)
			(layer "B.Fab")
		)
		(fp_line
			(start 0.2794 0.9906)
			(end -0.2794 0.9906)
			(stroke
				(width 0.1)
				(type default)
			)
			(layer "B.Fab")
		)
		(fp_line
			(start -0.2794 -0.1016)
			(end 0.2794 -0.1016)
			(stroke
				(width 0.1)
				(type default)
			)
			(layer "B.Fab")
		)
		(fp_line
			(start 0.2794 -0.1016)
			(end 0.2794 0.9906)
			(stroke
				(width 0.1)
				(type default)
			)
			(layer "B.Fab")
		)
		(pad "1" smd rect
			(at 0 0 90)
			(size 0.508 0.508)
			(layers "B.Cu" "B.Mask" "B.Paste")
			(net "PVCCIO_CPU1")
		)
		(pad "2" smd rect
			(at 0 0.889 90)
			(size 0.508 0.508)
			(layers "B.Cu" "B.Mask" "B.Paste")
			(net "SMB_DDR_GHJ_SDA_G")
		)
		(zone
			(layer "B.Cu")
			(hatch none 0.5)
			(connect_pads
				(clearance 0)
			)
			(min_thickness 0.25)
			(keepout
				(tracks not_allowed)
				(vias allowed)
				(pads allowed)
				(copperpour not_allowed)
				(footprints allowed)
			)
			(placement
				(enabled no)
				(sheetname "")
			)
			(fill
				(thermal_gap 0.5)
				(thermal_bridge_width 0.5)
				(island_removal_mode 0)
			)
			(polygon
				(pts
					(xy 169.135552 -23.308564) (xy 169.135552 -23.816564) (xy 169.516552 -23.816564) (xy 169.516552 -23.308564)
				)
			)
		)
		(zone
			(layer "B.Cu")
			(hatch none 0.5)
			(connect_pads
				(clearance 0)
			)
			(min_thickness 0.25)
			(keepout
				(tracks allowed)
				(vias not_allowed)
				(pads allowed)
				(copperpour not_allowed)
				(footprints allowed)
			)
			(placement
				(enabled no)
				(sheetname "")
			)
			(fill
				(thermal_gap 0.5)
				(thermal_bridge_width 0.5)
				(island_removal_mode 0)
			)
			(polygon
				(pts
					(xy 169.516552 -23.308564) (xy 169.516552 -23.816564) (xy 169.135552 -23.816564) (xy 169.135552 -23.308564)
				)
			)
		)
	)
	(footprint ""
		(layer "B.Cu")
		(at 460.8576 -126.7714)
		(property "Reference" "C1M37"
			(at 0 0 0)
			(layer "B.SilkS")
			(hide yes)
			(effects
				(font
					(size 1.27 1.27)
				)
				(justify mirror)
			)
		)
		(property "Value" ""
			(at 0 0 0)
			(layer "B.Fab")
			(effects
				(font
					(size 1.27 1.27)
				)
				(justify mirror)
			)
		)
		(duplicate_pad_numbers_are_jumpers no)
		(fp_poly
			(pts
				(xy -0.3048 -0.1016) (xy -0.3048 0.9906) (xy 0.3048 0.9906) (xy 0.3048 -0.1016)
			)
			(stroke
				(width 0)
				(type default)
			)
			(fill no)
			(layer "B.CrtYd")
		)
		(fp_line
			(start -0.3048 -0.1016)
			(end 0.3048 -0.1016)
			(stroke
				(width 0.1)
				(type default)
			)
			(layer "B.Fab")
		)
		(fp_line
			(start -0.3048 0.9906)
			(end -0.3048 -0.1016)
			(stroke
				(width 0.1)
				(type default)
			)
			(layer "B.Fab")
		)
		(fp_line
			(start 0.3048 -0.1016)
			(end 0.3048 0.9906)
			(stroke
				(width 0.1)
				(type default)
			)
			(layer "B.Fab")
		)
		(fp_line
			(start 0.3048 0.9906)
			(end -0.3048 0.9906)
			(stroke
				(width 0.1)
				(type default)
			)
			(layer "B.Fab")
		)
		(pad "1" smd rect
			(at 0 0 180)
			(size 0.508 0.508)
			(layers "B.Cu" "B.Mask" "B.Paste")
			(net "P3V3_STBY")
		)
		(pad "2" smd rect
			(at 0 0.889 180)
			(size 0.508 0.508)
			(layers "B.Cu" "B.Mask" "B.Paste")
			(net "GND")
		)
		(zone
			(layer "B.Cu")
			(hatch none 0.5)
			(connect_pads
				(clearance 0)
			)
			(min_thickness 0.25)
			(keepout
				(tracks allowed)
				(vias not_allowed)
				(pads allowed)
				(copperpour not_allowed)
				(footprints allowed)
			)
			(placement
				(enabled no)
				(sheetname "")
			)
			(fill
				(thermal_gap 0.5)
				(thermal_bridge_width 0.5)
				(island_removal_mode 0)
			)
			(polygon
				(pts
					(xy 461.1116 -126.5174) (xy 460.6036 -126.5174) (xy 460.6036 -126.1364) (xy 461.1116 -126.1364)
				)
			)
		)
		(zone
			(layer "B.Cu")
			(hatch none 0.5)
			(connect_pads
				(clearance 0)
			)
			(min_thickness 0.25)
			(keepout
				(tracks not_allowed)
				(vias allowed)
				(pads allowed)
				(copperpour not_allowed)
				(footprints allowed)
			)
			(placement
				(enabled no)
				(sheetname "")
			)
			(fill
				(thermal_gap 0.5)
				(thermal_bridge_width 0.5)
				(island_removal_mode 0)
			)
			(polygon
				(pts
					(xy 461.1116 -126.1364) (xy 460.6036 -126.1364) (xy 460.6036 -126.5174) (xy 461.1116 -126.5174)
				)
			)
		)
	)
	(footprint ""
		(layer "B.Cu")
		(at 351.421192 -77.834236)
		(property "Reference" "C3P29"
			(at 0 0 0)
			(layer "B.SilkS")
			(hide yes)
			(effects
				(font
					(size 1.27 1.27)
				)
				(justify mirror)
			)
		)
		(property "Value" ""
			(at 0 0 0)
			(layer "B.Fab")
			(effects
				(font
					(size 1.27 1.27)
				)
				(justify mirror)
			)
		)
		(duplicate_pad_numbers_are_jumpers no)
		(fp_poly
			(pts
				(xy -0.3048 -0.1016) (xy -0.3048 0.9906) (xy 0.3048 0.9906) (xy 0.3048 -0.1016)
			)
			(stroke
				(width 0)
				(type default)
			)
			(fill no)
			(layer "B.CrtYd")
		)
		(fp_line
			(start -0.3048 -0.1016)
			(end 0.3048 -0.1016)
			(stroke
				(width 0.1)
				(type default)
			)
			(layer "B.Fab")
		)
		(fp_line
			(start -0.3048 0.9906)
			(end -0.3048 -0.1016)
			(stroke
				(width 0.1)
				(type default)
			)
			(layer "B.Fab")
		)
		(fp_line
			(start 0.3048 -0.1016)
			(end 0.3048 0.9906)
			(stroke
				(width 0.1)
				(type default)
			)
			(layer "B.Fab")
		)
		(fp_line
			(start 0.3048 0.9906)
			(end -0.3048 0.9906)
			(stroke
				(width 0.1)
				(type default)
			)
			(layer "B.Fab")
		)
		(pad "1" smd rect
			(at 0 0 180)
			(size 0.508 0.508)
			(layers "B.Cu" "B.Mask" "B.Paste")
			(net "P3E_CPU0_PE1_SS_TXN<4>")
		)
		(pad "2" smd rect
			(at 0 0.889 180)
			(size 0.508 0.508)
			(layers "B.Cu" "B.Mask" "B.Paste")
			(net "P3E_CPU0_PE1_SS_C_TXN<4>")
		)
		(zone
			(layer "B.Cu")
			(hatch none 0.5)
			(connect_pads
				(clearance 0)
			)
			(min_thickness 0.25)
			(keepout
				(tracks allowed)
				(vias not_allowed)
				(pads allowed)
				(copperpour not_allowed)
				(footprints allowed)
			)
			(placement
				(enabled no)
				(sheetname "")
			)
			(fill
				(thermal_gap 0.5)
				(thermal_bridge_width 0.5)
				(island_removal_mode 0)
			)
			(polygon
				(pts
					(xy 351.675192 -77.580236) (xy 351.167192 -77.580236) (xy 351.167192 -77.199236) (xy 351.675192 -77.199236)
				)
			)
		)
		(zone
			(layer "B.Cu")
			(hatch none 0.5)
			(connect_pads
				(clearance 0)
			)
			(min_thickness 0.25)
			(keepout
				(tracks not_allowed)
				(vias allowed)
				(pads allowed)
				(copperpour not_allowed)
				(footprints allowed)
			)
			(placement
				(enabled no)
				(sheetname "")
			)
			(fill
				(thermal_gap 0.5)
				(thermal_bridge_width 0.5)
				(island_removal_mode 0)
			)
			(polygon
				(pts
					(xy 351.675192 -77.199236) (xy 351.167192 -77.199236) (xy 351.167192 -77.580236) (xy 351.675192 -77.580236)
				)
			)
		)
	)
	(footprint ""
		(layer "B.Cu")
		(at 441.833 -13.8938 90)
		(property "Reference" "C1U22"
			(at 0 0 90)
			(layer "B.SilkS")
			(hide yes)
			(effects
				(font
					(size 1.27 1.27)
				)
				(justify mirror)
			)
		)
		(property "Value" ""
			(at 0 0 90)
			(layer "B.Fab")
			(effects
				(font
					(size 1.27 1.27)
				)
				(justify mirror)
			)
		)
		(duplicate_pad_numbers_are_jumpers no)
		(fp_poly
			(pts
				(xy -0.3048 -0.1016) (xy -0.3048 0.9906) (xy 0.3048 0.9906) (xy 0.3048 -0.1016)
			)
			(stroke
				(width 0)
				(type default)
			)
			(fill no)
			(layer "B.CrtYd")
		)
		(fp_line
			(start 0.3048 -0.1016)
			(end 0.3048 0.9906)
			(stroke
				(width 0.1)
				(type default)
			)
			(layer "B.Fab")
		)
		(fp_line
			(start -0.3048 -0.1016)
			(end 0.3048 -0.1016)
			(stroke
				(width 0.1)
				(type default)
			)
			(layer "B.Fab")
		)
		(fp_line
			(start 0.3048 0.9906)
			(end -0.3048 0.9906)
			(stroke
				(width 0.1)
				(type default)
			)
			(layer "B.Fab")
		)
		(fp_line
			(start -0.3048 0.9906)
			(end -0.3048 -0.1016)
			(stroke
				(width 0.1)
				(type default)
			)
			(layer "B.Fab")
		)
		(pad "1" smd rect
			(at 0 0 270)
			(size 0.508 0.508)
			(layers "B.Cu" "B.Mask" "B.Paste")
			(net "P0V7_GTL2014_2")
		)
		(pad "2" smd rect
			(at 0 0.889 270)
			(size 0.508 0.508)
			(layers "B.Cu" "B.Mask" "B.Paste")
			(net "GND")
		)
		(zone
			(layer "B.Cu")
			(hatch none 0.5)
			(connect_pads
				(clearance 0)
			)
			(min_thickness 0.25)
			(keepout
				(tracks allowed)
				(vias not_allowed)
				(pads allowed)
				(copperpour not_allowed)
				(footprints allowed)
			)
			(placement
				(enabled no)
				(sheetname "")
			)
			(fill
				(thermal_gap 0.5)
				(thermal_bridge_width 0.5)
				(island_removal_mode 0)
			)
			(polygon
				(pts
					(xy 442.087 -14.1478) (xy 442.087 -13.6398) (xy 442.468 -13.6398) (xy 442.468 -14.1478)
				)
			)
		)
		(zone
			(layer "B.Cu")
			(hatch none 0.5)
			(connect_pads
				(clearance 0)
			)
			(min_thickness 0.25)
			(keepout
				(tracks not_allowed)
				(vias allowed)
				(pads allowed)
				(copperpour not_allowed)
				(footprints allowed)
			)
			(placement
				(enabled no)
				(sheetname "")
			)
			(fill
				(thermal_gap 0.5)
				(thermal_bridge_width 0.5)
				(island_removal_mode 0)
			)
			(polygon
				(pts
					(xy 442.468 -14.1478) (xy 442.468 -13.6398) (xy 442.087 -13.6398) (xy 442.087 -14.1478)
				)
			)
		)
	)
)
